(kicad_pcb
	(version 20240108)
	(generator "pcbnew")
	(generator_version "8.0")
	(general
		(thickness 1.62)
		(legacy_teardrops no)
	)
	(paper "A4")
	(title_block
		(title "Jetson Orin Baseboard")
		(date "2025-03-12")
		(rev "1.3.4")
		(company "Antmicro Ltd")
		(comment 1 "www.antmicro.com")
		(comment 9 "footprints 538-541 of 677")
	)
	(layers
		(0 "F.Cu" signal)
		(1 "In1.Cu" signal)
		(2 "In2.Cu" signal)
		(3 "In3.Cu" signal)
		(4 "In4.Cu" jumper)
		(5 "In5.Cu" signal)
		(6 "In6.Cu" signal)
		(31 "B.Cu" signal)
		(32 "B.Adhes" user "B.Adhesive")
		(33 "F.Adhes" user "F.Adhesive")
		(34 "B.Paste" user)
		(35 "F.Paste" user)
		(36 "B.SilkS" user "B.Silkscreen")
		(37 "F.SilkS" user "F.Silkscreen")
		(38 "B.Mask" user)
		(39 "F.Mask" user)
		(40 "Dwgs.User" user "User.Drawings")
		(41 "Cmts.User" user "User.Comments")
		(42 "Eco1.User" user "User.Eco1")
		(43 "Eco2.User" user "User.Eco2")
		(44 "Edge.Cuts" user)
		(45 "Margin" user)
		(46 "B.CrtYd" user "B.Courtyard")
		(47 "F.CrtYd" user "F.Courtyard")
		(48 "B.Fab" user)
		(49 "F.Fab" user)
	)
	(footprint "antmicro-footprints:R_0402_1005Metric"
		(layer "B.Cu")
		(at 46.54 74.475 180)
		(descr "Resistor SMD 0402")
		(tags "resistor SMD 0402")
		(property "Reference" "R255"
			(at -1.36 -2.225 0)
			(layer "B.SilkS")
			(effects
				(font
					(size 0.7 0.7)
					(thickness 0.15)
				)
				(justify left bottom mirror)
			)
		)
		(property "Value" "R_10k_0402"
			(at 0 -1.4 0)
			(layer "B.Fab")
			(effects
				(font
					(size 0.7 0.7)
					(thickness 0.15)
				)
				(justify left bottom mirror)
			)
		)
		(property "Footprint" "antmicro-footprints:R_0402_1005Metric"
			(at 0 0 180)
			(layer "F.Fab")
			(hide yes)
			(effects
				(font
					(size 1.27 1.27)
					(thickness 0.15)
				)
			)
		)
		(property "Datasheet" "https://www.bourns.com/docs/product-datasheets/cr.pdf"
			(at 0 0 180)
			(layer "F.Fab")
			(hide yes)
			(effects
				(font
					(size 1.27 1.27)
					(thickness 0.15)
				)
			)
		)
		(property "Author" "Antmicro"
			(at 93.8 148.8 0)
			(layer "B.Fab")
			(hide yes)
			(effects
				(font
					(size 1 1)
					(thickness 0.15)
				)
				(justify mirror)
			)
		)
		(property "License" "Apache-2.0"
			(at 93.8 148.8 0)
			(layer "B.Fab")
			(hide yes)
			(effects
				(font
					(size 1 1)
					(thickness 0.15)
				)
				(justify mirror)
			)
		)
		(property "MPN" "CR0402-FX-1002GLF"
			(at 93.8 148.8 0)
			(layer "B.Fab")
			(hide yes)
			(effects
				(font
					(size 1 1)
					(thickness 0.15)
				)
				(justify mirror)
			)
		)
		(property "Manufacturer" "Bourns"
			(at 93.8 148.8 0)
			(layer "B.Fab")
			(hide yes)
			(effects
				(font
					(size 1 1)
					(thickness 0.15)
				)
				(justify mirror)
			)
		)
		(property "Tolerance" "1%"
			(at 93.8 148.8 0)
			(layer "B.Fab")
			(hide yes)
			(effects
				(font
					(size 1 1)
					(thickness 0.15)
				)
				(justify mirror)
			)
		)
		(property "Val" "10k"
			(at 93.8 148.8 0)
			(layer "B.Fab")
			(hide yes)
			(effects
				(font
					(size 1 1)
					(thickness 0.15)
				)
				(justify mirror)
			)
		)
		(sheetname "Supply")
		(sheetfile "supply.kicad_sch")
		(attr smd)
		(fp_rect
			(start -0.925 0.47)
			(end 0.925 -0.47)
			(stroke
				(width 0.05)
				(type default)
			)
			(fill none)
			(layer "B.CrtYd")
		)
		(fp_rect
			(start -0.5 0.25)
			(end 0.5 -0.25)
			(stroke
				(width 0.15)
				(type solid)
			)
			(fill none)
			(layer "B.Fab")
		)
		(fp_text user "Author: Antmicro"
			(at -0.95 -4.169 0)
			(layer "B.Fab")
			(hide yes)
			(effects
				(font
					(size 0.7 0.7)
					(thickness 0.15)
				)
				(justify left bottom mirror)
			)
		)
		(fp_text user "License: Apache-2.0"
			(at -0.95 -5.169 0)
			(layer "B.Fab")
			(hide yes)
			(effects
				(font
					(size 0.7 0.7)
					(thickness 0.15)
				)
				(justify left bottom mirror)
			)
		)
		(fp_text user "${REFERENCE}"
			(at -0.95 -3.168 0)
			(layer "B.Fab")
			(hide yes)
			(effects
				(font
					(size 0.7 0.7)
					(thickness 0.15)
				)
				(justify left bottom mirror)
			)
		)
		(pad "1" smd roundrect
			(at -0.48 0 180)
			(size 0.59 0.64)
			(layers "B.Cu" "B.Paste" "B.Mask")
			(roundrect_rratio 0.25)
			(net 1 "GND")
			(pintype "passive")
		)
		(pad "2" smd roundrect
			(at 0.48 0 180)
			(size 0.59 0.64)
			(layers "B.Cu" "B.Paste" "B.Mask")
			(roundrect_rratio 0.25)
			(net 631 "Net-(Q16-G)")
			(pintype "passive")
		)
	)
	(footprint "antmicro-footprints:R_0402_1005Metric"
		(layer "B.Cu")
		(at 90 112.6 90)
		(descr "Resistor SMD 0402")
		(tags "resistor SMD 0402")
		(property "Reference" "R1"
			(at 0.965 -3.57 -90)
			(layer "B.SilkS")
			(effects
				(font
					(size 0.7 0.7)
					(thickness 0.15)
				)
				(justify left bottom mirror)
			)
		)
		(property "Value" "R_0R_0402"
			(at 0 -1.4 -90)
			(layer "B.Fab")
			(effects
				(font
					(size 0.7 0.7)
					(thickness 0.15)
				)
				(justify left bottom mirror)
			)
		)
		(property "Footprint" "antmicro-footprints:R_0402_1005Metric"
			(at 0 0 90)
			(layer "F.Fab")
			(hide yes)
			(effects
				(font
					(size 1.27 1.27)
					(thickness 0.15)
				)
			)
		)
		(property "Datasheet" "https://industrial.panasonic.com/cdbs/www-data/pdf/RDA0000/AOA0000C301.pdf"
			(at 0 0 90)
			(layer "F.Fab")
			(hide yes)
			(effects
				(font
					(size 1.27 1.27)
					(thickness 0.15)
				)
			)
		)
		(property "Author" "Antmicro"
			(at 202.6 22.6 0)
			(layer "B.Fab")
			(hide yes)
			(effects
				(font
					(size 1 1)
					(thickness 0.15)
				)
				(justify mirror)
			)
		)
		(property "Current" "1A"
			(at 202.6 22.6 0)
			(layer "B.Fab")
			(hide yes)
			(effects
				(font
					(size 1 1)
					(thickness 0.15)
				)
				(justify mirror)
			)
		)
		(property "License" "Apache-2.0"
			(at 202.6 22.6 0)
			(layer "B.Fab")
			(hide yes)
			(effects
				(font
					(size 1 1)
					(thickness 0.15)
				)
				(justify mirror)
			)
		)
		(property "MPN" "ERJ2GE0R00X"
			(at 202.6 22.6 0)
			(layer "B.Fab")
			(hide yes)
			(effects
				(font
					(size 1 1)
					(thickness 0.15)
				)
				(justify mirror)
			)
		)
		(property "Manufacturer" "Panasonic"
			(at 202.6 22.6 0)
			(layer "B.Fab")
			(hide yes)
			(effects
				(font
					(size 1 1)
					(thickness 0.15)
				)
				(justify mirror)
			)
		)
		(property "Tolerance" ""
			(at 202.6 22.6 0)
			(layer "B.Fab")
			(hide yes)
			(effects
				(font
					(size 1 1)
					(thickness 0.15)
				)
				(justify mirror)
			)
		)
		(property "Val" "0R"
			(at 202.6 22.6 0)
			(layer "B.Fab")
			(hide yes)
			(effects
				(font
					(size 1 1)
					(thickness 0.15)
				)
				(justify mirror)
			)
		)
		(sheetname "SoM")
		(sheetfile "som.kicad_sch")
		(attr smd)
		(fp_rect
			(start -0.925 0.47)
			(end 0.925 -0.47)
			(stroke
				(width 0.05)
				(type default)
			)
			(fill none)
			(layer "B.CrtYd")
		)
		(fp_rect
			(start -0.5 0.25)
			(end 0.5 -0.25)
			(stroke
				(width 0.15)
				(type solid)
			)
			(fill none)
			(layer "B.Fab")
		)
		(fp_text user "${REFERENCE}"
			(at -0.95 -3.168 -90)
			(layer "B.Fab")
			(hide yes)
			(effects
				(font
					(size 0.7 0.7)
					(thickness 0.15)
				)
				(justify left bottom mirror)
			)
		)
		(fp_text user "License: Apache-2.0"
			(at -0.95 -5.169 -90)
			(layer "B.Fab")
			(hide yes)
			(effects
				(font
					(size 0.7 0.7)
					(thickness 0.15)
				)
				(justify left bottom mirror)
			)
		)
		(fp_text user "Author: Antmicro"
			(at -0.95 -4.169 -90)
			(layer "B.Fab")
			(hide yes)
			(effects
				(font
					(size 0.7 0.7)
					(thickness 0.15)
				)
				(justify left bottom mirror)
			)
		)
		(pad "1" smd roundrect
			(at -0.48 0 90)
			(size 0.59 0.64)
			(layers "B.Cu" "B.Paste" "B.Mask")
			(roundrect_rratio 0.25)
			(net 747 "Net-(J15H-GPIO02)")
			(pintype "passive")
		)
		(pad "2" smd roundrect
			(at 0.48 0 90)
			(size 0.59 0.64)
			(layers "B.Cu" "B.Paste" "B.Mask")
			(roundrect_rratio 0.25)
			(net 281 "~{GPIO_INT}")
			(pintype "passive")
		)
	)
	(footprint "antmicro-footprints:C_0402_1005Metric"
		(layer "B.Cu")
		(at 55.25 82.75 90)
		(descr "Capacitor SMD 0402")
		(tags "capacitor SMD 0402")
		(property "Reference" "C160"
			(at -1.95 1.45 90)
			(layer "B.SilkS")
			(effects
				(font
					(size 0.7 0.7)
					(thickness 0.15)
				)
				(justify right top mirror)
			)
		)
		(property "Value" "C_1n_0402"
			(at -1.022927 -2.155213 90)
			(layer "B.Fab")
			(effects
				(font
					(size 0.7 0.7)
					(thickness 0.15)
				)
				(justify right top mirror)
			)
		)
		(property "Footprint" "antmicro-footprints:C_0402_1005Metric"
			(at 0 0 90)
			(layer "B.Fab")
			(hide yes)
			(effects
				(font
					(size 1.27 1.27)
					(thickness 0.15)
				)
				(justify mirror)
			)
		)
		(property "Datasheet" "https://www.murata.com/products/productdetail?partno=GRM1555C1H102JA01%23"
			(at 0 0 90)
			(layer "B.Fab")
			(hide yes)
			(effects
				(font
					(size 1.27 1.27)
					(thickness 0.15)
				)
				(justify mirror)
			)
		)
		(property "Description" "SMD Multilayer Ceramic Capacitor, 1000 pF, 50 V, 0402 [1005 Metric], ± 5%, C0G / NP0, GRM Series"
			(at 0 0 90)
			(layer "B.Fab")
			(hide yes)
			(effects
				(font
					(size 1.27 1.27)
					(thickness 0.15)
				)
				(justify mirror)
			)
		)
		(property "MPN" "GRM1555C1H102JA01D"
			(at 0 0 -90)
			(unlocked yes)
			(layer "B.Fab")
			(hide yes)
			(effects
				(font
					(size 1 1)
					(thickness 0.15)
				)
				(justify mirror)
			)
		)
		(property "Manufacturer" "Murata"
			(at 0 0 -90)
			(unlocked yes)
			(layer "B.Fab")
			(hide yes)
			(effects
				(font
					(size 1 1)
					(thickness 0.15)
				)
				(justify mirror)
			)
		)
		(property "License" "Apache-2.0"
			(at 0 0 -90)
			(unlocked yes)
			(layer "B.Fab")
			(hide yes)
			(effects
				(font
					(size 1 1)
					(thickness 0.15)
				)
				(justify mirror)
			)
		)
		(property "Author" "Antmicro"
			(at 0 0 -90)
			(unlocked yes)
			(layer "B.Fab")
			(hide yes)
			(effects
				(font
					(size 1 1)
					(thickness 0.15)
				)
				(justify mirror)
			)
		)
		(property "Val" "1n"
			(at 0 0 -90)
			(unlocked yes)
			(layer "B.Fab")
			(hide yes)
			(effects
				(font
					(size 1 1)
					(thickness 0.15)
				)
				(justify mirror)
			)
		)
		(property "Voltage" "50V"
			(at 0 0 -90)
			(unlocked yes)
			(layer "B.Fab")
			(hide yes)
			(effects
				(font
					(size 1 1)
					(thickness 0.15)
				)
				(justify mirror)
			)
		)
		(property "Dielectric" "C0G"
			(at 0 0 -90)
			(unlocked yes)
			(layer "B.Fab")
			(hide yes)
			(effects
				(font
					(size 1 1)
					(thickness 0.15)
				)
				(justify mirror)
			)
		)
		(sheetname "Supply")
		(sheetfile "supply.kicad_sch")
		(attr smd)
		(fp_rect
			(start -0.925 0.47)
			(end 0.925 -0.47)
			(stroke
				(width 0.05)
				(type default)
			)
			(fill none)
			(layer "B.CrtYd")
		)
		(fp_line
			(start 0.504 -0.248)
			(end 0.504 0.25)
			(stroke
				(width 0.15)
				(type solid)
			)
			(layer "B.Fab")
		)
		(fp_line
			(start -0.494 -0.248)
			(end 0.504 -0.248)
			(stroke
				(width 0.15)
				(type solid)
			)
			(layer "B.Fab")
		)
		(fp_line
			(start 0.504 0.25)
			(end -0.494 0.25)
			(stroke
				(width 0.15)
				(type solid)
			)
			(layer "B.Fab")
		)
		(fp_line
			(start -0.494 0.25)
			(end -0.494 -0.248)
			(stroke
				(width 0.15)
				(type solid)
			)
			(layer "B.Fab")
		)
		(fp_text user "${REFERENCE}"
			(at -0.939 -4.599 90)
			(layer "B.Fab")
			(hide yes)
			(effects
				(font
					(size 0.7 0.7)
					(thickness 0.15)
				)
				(justify right top mirror)
			)
		)
		(fp_text user "Author: Antmicro"
			(at -0.939 -3.399 90)
			(layer "B.Fab")
			(hide yes)
			(effects
				(font
					(size 0.7 0.7)
					(thickness 0.15)
				)
				(justify right top mirror)
			)
		)
		(fp_text user "License: Apache-2.0"
			(at -0.939 -5.799 90)
			(layer "B.Fab")
			(hide yes)
			(effects
				(font
					(size 0.7 0.7)
					(thickness 0.15)
				)
				(justify right top mirror)
			)
		)
		(pad "1" smd roundrect
			(at -0.48 0 90)
			(size 0.59 0.64)
			(layers "B.Cu" "B.Paste" "B.Mask")
			(roundrect_rratio 0.25)
			(net 1 "GND")
			(pintype "passive")
		)
		(pad "2" smd roundrect
			(at 0.48 0 90)
			(size 0.59 0.64)
			(layers "B.Cu" "B.Paste" "B.Mask")
			(roundrect_rratio 0.25)
			(net 644 "Net-(U48-DVDT)")
			(pintype "passive")
		)
	)
	(footprint "antmicro-footprints:R_0402_1005Metric"
		(layer "B.Cu")
		(at 38.608 117.856 90)
		(descr "Resistor SMD 0402")
		(tags "resistor SMD 0402")
		(property "Reference" "R147"
			(at 1.206 -1.458 -90)
			(layer "B.SilkS")
			(effects
				(font
					(size 0.7 0.7)
					(thickness 0.15)
				)
				(justify left bottom mirror)
			)
		)
		(property "Value" "R_200R_0402"
			(at 0 -1.4 -90)
			(layer "B.Fab")
			(effects
				(font
					(size 0.7 0.7)
					(thickness 0.15)
				)
				(justify left bottom mirror)
			)
		)
		(property "Footprint" "antmicro-footprints:R_0402_1005Metric"
			(at 0 0 90)
			(layer "F.Fab")
			(hide yes)
			(effects
				(font
					(size 1.27 1.27)
					(thickness 0.15)
				)
			)
		)
		(property "Datasheet" "https://www.bourns.com/docs/product-datasheets/cr.pdf"
			(at 0 0 90)
			(layer "F.Fab")
			(hide yes)
			(effects
				(font
					(size 1.27 1.27)
					(thickness 0.15)
				)
			)
		)
		(property "Author" "Antmicro"
			(at 156.464 79.248 0)
			(layer "B.Fab")
			(hide yes)
			(effects
				(font
					(size 1 1)
					(thickness 0.15)
				)
				(justify mirror)
			)
		)
		(property "License" "Apache-2.0"
			(at 156.464 79.248 0)
			(layer "B.Fab")
			(hide yes)
			(effects
				(font
					(size 1 1)
					(thickness 0.15)
				)
				(justify mirror)
			)
		)
		(property "MPN" "CR0402-FX-2000GLF"
			(at 156.464 79.248 0)
			(layer "B.Fab")
			(hide yes)
			(effects
				(font
					(size 1 1)
					(thickness 0.15)
				)
				(justify mirror)
			)
		)
		(property "Manufacturer" "Bourns"
			(at 156.464 79.248 0)
			(layer "B.Fab")
			(hide yes)
			(effects
				(font
					(size 1 1)
					(thickness 0.15)
				)
				(justify mirror)
			)
		)
		(property "Tolerance" "1%"
			(at 156.464 79.248 0)
			(layer "B.Fab")
			(hide yes)
			(effects
				(font
					(size 1 1)
					(thickness 0.15)
				)
				(justify mirror)
			)
		)
		(property "Val" "200R"
			(at 156.464 79.248 0)
			(layer "B.Fab")
			(hide yes)
			(effects
				(font
					(size 1 1)
					(thickness 0.15)
				)
				(justify mirror)
			)
		)
		(sheetname "Ethernet")
		(sheetfile "ethernet.kicad_sch")
		(attr smd)
		(fp_rect
			(start -0.925 0.47)
			(end 0.925 -0.47)
			(stroke
				(width 0.05)
				(type default)
			)
			(fill none)
			(layer "B.CrtYd")
		)
		(fp_rect
			(start -0.5 0.25)
			(end 0.5 -0.25)
			(stroke
				(width 0.15)
				(type solid)
			)
			(fill none)
			(layer "B.Fab")
		)
		(fp_text user "${REFERENCE}"
			(at -0.95 -3.168 -90)
			(layer "B.Fab")
			(hide yes)
			(effects
				(font
					(size 0.7 0.7)
					(thickness 0.15)
				)
				(justify left bottom mirror)
			)
		)
		(fp_text user "Author: Antmicro"
			(at -0.95 -4.169 -90)
			(layer "B.Fab")
			(hide yes)
			(effects
				(font
					(size 0.7 0.7)
					(thickness 0.15)
				)
				(justify left bottom mirror)
			)
		)
		(fp_text user "License: Apache-2.0"
			(at -0.95 -5.169 -90)
			(layer "B.Fab")
			(hide yes)
			(effects
				(font
					(size 0.7 0.7)
					(thickness 0.15)
				)
				(justify left bottom mirror)
			)
		)
		(pad "1" smd roundrect
			(at -0.48 0 90)
			(size 0.59 0.64)
			(layers "B.Cu" "B.Paste" "B.Mask")
			(roundrect_rratio 0.25)
			(net 1 "GND")
			(pintype "passive")
		)
		(pad "2" smd roundrect
			(at 0.48 0 90)
			(size 0.59 0.64)
			(layers "B.Cu" "B.Paste" "B.Mask")
			(roundrect_rratio 0.25)
			(net 715 "Net-(C78-Pad1)")
			(pintype "passive")
		)
	)
)
